# S9S_MB_2U (Grand Teton) — schematic netlist excerpt (pin names and nets, part order shuffled) for the footprints in the layout excerpt that follows; sources: Cadence DE-HDL packaged netlist, KiCad conversion of 03242023_DA0F0TMBIJ0_F0T_Motherboard_J_brd_V01_OCP.brd

H36  HOLE  EMPTY  pkg TH  page 311 : \1\ = NC
R722  Q_RES  1K 1% EMPTY  pkg 0402LF  page 243 : A = MB_FRU_ADDR0 ; B = GND
C213  Q_CAP  47UF 4V 20% X6S  pkg C0805  page 74 : A = PVCCIN_CPU0 ; B = GND

(kicad_pcb
	(version 20260206)
	(generator "pcbnew")
	(generator_version "10.0")
	(general
		(thickness 1.6)
		(legacy_teardrops no)
	)
	(paper "A4")
	(title_block
		(title "03242023_DA0F0TMBIJ0_F0T_Motherboard_J_brd_V01_OCP.brd")
		(comment 1 "Grand Teton / footprints 1789-1791 of 6105")
	)
	(layers
		(0 "F.Cu" signal "TOP")
		(4 "In1.Cu" signal "GND")
		(6 "In2.Cu" signal "IN1")
		(8 "In3.Cu" signal "GND1")
		(10 "In4.Cu" signal "IN2")
		(12 "In5.Cu" signal "GND2")
		(14 "In6.Cu" signal "IN3")
		(16 "In7.Cu" signal "GND3")
		(18 "In8.Cu" signal "VCC")
		(20 "In9.Cu" signal "VCC1")
		(22 "In10.Cu" signal "GND4")
		(24 "In11.Cu" signal "IN4")
		(26 "In12.Cu" signal "GND5")
		(28 "In13.Cu" signal "IN5")
		(30 "In14.Cu" signal "GND6")
		(32 "In15.Cu" signal "IN6")
		(34 "In16.Cu" signal "GND7")
		(2 "B.Cu" signal "BOTTOM")
		(9 "F.Adhes" user "F.Adhesive")
		(11 "B.Adhes" user "B.Adhesive")
		(13 "F.Paste" user "Package Geometry/Pastemask Top")
		(15 "B.Paste" user "Package Geometry/Pastemask Bottom")
		(5 "F.SilkS" user "Ref Des/Silkscreen Top")
		(7 "B.SilkS" user "Ref Des/Silkscreen Bottom")
		(1 "F.Mask" user "Board Geometry/Soldermask Top")
		(3 "B.Mask" user "Board Geometry/Soldermask Bottom")
		(17 "Dwgs.User" user "User.Drawings")
		(19 "Cmts.User" user "User.Comments")
		(21 "Eco1.User" user "User.Eco1")
		(23 "Eco2.User" user "User.Eco2")
		(25 "Edge.Cuts" user "Board Geometry/Outline")
		(27 "Margin" user)
		(31 "F.CrtYd" user "Package Geometry/Place Bound Top")
		(29 "B.CrtYd" user "Package Geometry/Place Bound Bottom")
		(35 "F.Fab" user "Ref Des/Assembly Top")
		(33 "B.Fab" user "Ref Des/Assembly Bottom")
	)
	(footprint ""
		(layer "F.Cu")
		(at 274.72894 -96.329754 180)
		(property "Reference" "R722"
			(at 0 0 180)
			(layer "F.SilkS")
			(hide yes)
			(effects
				(font
					(size 1.27 1.27)
				)
			)
		)
		(property "Value" ""
			(at 0 0 180)
			(layer "F.Fab")
			(effects
				(font
					(size 1.27 1.27)
				)
			)
		)
		(duplicate_pad_numbers_are_jumpers no)
		(fp_line
			(start 0.7874 0.4064)
			(end -0.7874 0.4064)
			(stroke
				(width 0.1524)
				(type default)
			)
			(layer "F.SilkS")
		)
		(fp_line
			(start 0.7874 -0.4064)
			(end 0.7874 0.4064)
			(stroke
				(width 0.1524)
				(type default)
			)
			(layer "F.SilkS")
		)
		(fp_line
			(start -0.7874 0.4064)
			(end -0.7874 -0.4064)
			(stroke
				(width 0.1524)
				(type default)
			)
			(layer "F.SilkS")
		)
		(fp_line
			(start -0.7874 -0.4064)
			(end 0.7874 -0.4064)
			(stroke
				(width 0.1524)
				(type default)
			)
			(layer "F.SilkS")
		)
		(fp_line
			(start 0.67945 0.3048)
			(end 0.120396 0.3048)
			(stroke
				(width 0.1)
				(type default)
			)
			(layer "F.Fab")
		)
		(fp_line
			(start 0.67945 -0.3048)
			(end 0.67945 0.3048)
			(stroke
				(width 0.1)
				(type default)
			)
			(layer "F.Fab")
		)
		(fp_line
			(start 0.12065 -0.2794)
			(end 0.12065 -0.3048)
			(stroke
				(width 0.1)
				(type default)
			)
			(layer "F.Fab")
		)
		(fp_line
			(start 0.12065 -0.3048)
			(end 0.67945 -0.3048)
			(stroke
				(width 0.1)
				(type default)
			)
			(layer "F.Fab")
		)
		(fp_line
			(start 0.120396 0.3048)
			(end 0.120396 0.2794)
			(stroke
				(width 0.1)
				(type default)
			)
			(layer "F.Fab")
		)
		(fp_line
			(start 0.120396 0.2794)
			(end -0.12065 0.2794)
			(stroke
				(width 0.1)
				(type default)
			)
			(layer "F.Fab")
		)
		(fp_line
			(start -0.12065 0.3048)
			(end -0.67945 0.3048)
			(stroke
				(width 0.1)
				(type default)
			)
			(layer "F.Fab")
		)
		(fp_line
			(start -0.12065 0.2794)
			(end -0.12065 0.3048)
			(stroke
				(width 0.1)
				(type default)
			)
			(layer "F.Fab")
		)
		(fp_line
			(start -0.12065 -0.2794)
			(end 0.12065 -0.2794)
			(stroke
				(width 0.1)
				(type default)
			)
			(layer "F.Fab")
		)
		(fp_line
			(start -0.12065 -0.305054)
			(end -0.12065 -0.2794)
			(stroke
				(width 0.1)
				(type default)
			)
			(layer "F.Fab")
		)
		(fp_line
			(start -0.67945 0.3048)
			(end -0.67945 -0.305054)
			(stroke
				(width 0.1)
				(type default)
			)
			(layer "F.Fab")
		)
		(fp_line
			(start -0.67945 -0.305054)
			(end -0.12065 -0.305054)
			(stroke
				(width 0.1)
				(type default)
			)
			(layer "F.Fab")
		)
		(pad "1" smd circle
			(at -0.40005 0 180)
			(size 0 0)
			(layers "F.Cu" "F.Mask" "F.Paste")
			(net "MB_FRU_ADDR0")
		)
		(pad "2" smd circle
			(at 0.40005 0 180)
			(size 0 0)
			(layers "F.Cu" "F.Mask" "F.Paste")
			(net "GND")
		)
	)
	(footprint ""
		(layer "F.Cu")
		(at 362.89488 -296.05478)
		(property "Reference" "C213"
			(at 0 0 0)
			(layer "F.SilkS")
			(hide yes)
			(effects
				(font
					(size 1.27 1.27)
				)
			)
		)
		(property "Value" ""
			(at 0 0 0)
			(layer "F.Fab")
			(effects
				(font
					(size 1.27 1.27)
				)
			)
		)
		(duplicate_pad_numbers_are_jumpers no)
		(fp_line
			(start -1.524 -0.762)
			(end 1.524 -0.762)
			(stroke
				(width 0.1524)
				(type default)
			)
			(layer "F.SilkS")
		)
		(fp_line
			(start -1.524 0.762)
			(end -1.524 -0.762)
			(stroke
				(width 0.1524)
				(type default)
			)
			(layer "F.SilkS")
		)
		(fp_line
			(start 1.524 -0.762)
			(end 1.524 0.762)
			(stroke
				(width 0.1524)
				(type default)
			)
			(layer "F.SilkS")
		)
		(fp_line
			(start 1.524 0.762)
			(end -1.524 0.762)
			(stroke
				(width 0.1524)
				(type default)
			)
			(layer "F.SilkS")
		)
		(fp_line
			(start -1.1049 -0.724916)
			(end -1.1049 0.724916)
			(stroke
				(width 0.1)
				(type default)
			)
			(layer "F.Fab")
		)
		(fp_line
			(start -1.1049 0.724916)
			(end 1.1049 0.724916)
			(stroke
				(width 0.1)
				(type default)
			)
			(layer "F.Fab")
		)
		(fp_line
			(start 1.1049 -0.724916)
			(end -1.1049 -0.724916)
			(stroke
				(width 0.1)
				(type default)
			)
			(layer "F.Fab")
		)
		(fp_line
			(start 1.1049 0.724916)
			(end 1.1049 -0.724916)
			(stroke
				(width 0.1)
				(type default)
			)
			(layer "F.Fab")
		)
		(pad "1" smd rect
			(at -0.889 0 180)
			(size 1.016 1.27)
			(layers "F.Cu" "F.Mask" "F.Paste")
			(net "PVCCIN_CPU0")
		)
		(pad "2" smd rect
			(at 0.889 0 180)
			(size 1.016 1.27)
			(layers "F.Cu" "F.Mask" "F.Paste")
			(net "GND")
		)
	)
	(footprint ""
		(layer "F.Cu")
		(at 356.899972 -28.450032)
		(property "Reference" "H36"
			(at 3.200908 -2.585466 0)
			(unlocked yes)
			(layer "F.SilkS")
			(effects
				(font
					(size 0.7874 0.5842)
					(thickness 0.1524)
				)
				(justify left)
			)
		)
		(property "Value" ""
			(at 0 0 0)
			(layer "F.Fab")
			(effects
				(font
					(size 1.27 1.27)
				)
			)
		)
		(duplicate_pad_numbers_are_jumpers no)
		(fp_circle
			(center 0 0)
			(end 2.3622 0)
			(stroke
				(width 0.1524)
				(type default)
			)
			(fill no)
			(layer "F.SilkS")
		)
		(fp_circle
			(center 0 0)
			(end 2.3622 0)
			(stroke
				(width 0.1524)
				(type default)
			)
			(fill no)
			(layer "B.SilkS")
		)
		(fp_circle
			(center 0 0)
			(end 2.3622 0)
			(stroke
				(width 0.1)
				(type default)
			)
			(fill no)
			(layer "B.Fab")
		)
		(fp_circle
			(center 0 0)
			(end 2.3622 0)
			(stroke
				(width 0.1)
				(type default)
			)
			(fill no)
			(layer "F.Fab")
		)
		(pad "" np_thru_hole circle
			(at 0 0)
			(size 3.0988 3.0988)
			(drill 3.0988)
			(layers "*.Cu" "*.Mask")
			(clearance 0.254)
			(thermal_gap 0.254)
		)
	)
)
